(kicad_pcb
	(version 20260206)
	(generator "pcbnew")
	(generator_version "10.0")
	(general
		(thickness 1.6)
		(legacy_teardrops no)
	)
	(paper "A4")
	(title_block
		(title "03242023_DA0F0TMBIJ0_F0T_Motherboard_J_brd_V01_OCP.brd")
		(comment 1 "Grand Teton / footprints 3787-3793 of 6105")
	)
	(layers
		(0 "F.Cu" signal "TOP")
		(4 "In1.Cu" signal "GND")
		(6 "In2.Cu" signal "IN1")
		(8 "In3.Cu" signal "GND1")
		(10 "In4.Cu" signal "IN2")
		(12 "In5.Cu" signal "GND2")
		(14 "In6.Cu" signal "IN3")
		(16 "In7.Cu" signal "GND3")
		(18 "In8.Cu" signal "VCC")
		(20 "In9.Cu" signal "VCC1")
		(22 "In10.Cu" signal "GND4")
		(24 "In11.Cu" signal "IN4")
		(26 "In12.Cu" signal "GND5")
		(28 "In13.Cu" signal "IN5")
		(30 "In14.Cu" signal "GND6")
		(32 "In15.Cu" signal "IN6")
		(34 "In16.Cu" signal "GND7")
		(2 "B.Cu" signal "BOTTOM")
		(9 "F.Adhes" user "F.Adhesive")
		(11 "B.Adhes" user "B.Adhesive")
		(13 "F.Paste" user "Package Geometry/Pastemask Top")
		(15 "B.Paste" user "Package Geometry/Pastemask Bottom")
		(5 "F.SilkS" user "Ref Des/Silkscreen Top")
		(7 "B.SilkS" user "Ref Des/Silkscreen Bottom")
		(1 "F.Mask" user "Board Geometry/Soldermask Top")
		(3 "B.Mask" user "Board Geometry/Soldermask Bottom")
		(17 "Dwgs.User" user "User.Drawings")
		(19 "Cmts.User" user "User.Comments")
		(21 "Eco1.User" user "User.Eco1")
		(23 "Eco2.User" user "User.Eco2")
		(25 "Edge.Cuts" user "Board Geometry/Outline")
		(27 "Margin" user)
		(31 "F.CrtYd" user "Package Geometry/Place Bound Top")
		(29 "B.CrtYd" user "Package Geometry/Place Bound Bottom")
		(35 "F.Fab" user "Ref Des/Assembly Top")
		(33 "B.Fab" user "Ref Des/Assembly Bottom")
	)
	(footprint ""
		(layer "F.Cu")
		(at 330.721208 -408.517344 -90)
		(property "Reference" "C919"
			(at 0 0 270)
			(layer "F.SilkS")
			(hide yes)
			(effects
				(font
					(size 1.27 1.27)
				)
			)
		)
		(property "Value" ""
			(at 0 0 270)
			(layer "F.Fab")
			(effects
				(font
					(size 1.27 1.27)
				)
			)
		)
		(duplicate_pad_numbers_are_jumpers no)
		(fp_line
			(start -0.299974 0.150114)
			(end -0.299974 -0.150114)
			(stroke
				(width 0.1)
				(type default)
			)
			(layer "F.Fab")
		)
		(fp_line
			(start 0.299974 0.150114)
			(end -0.299974 0.150114)
			(stroke
				(width 0.1)
				(type default)
			)
			(layer "F.Fab")
		)
		(fp_line
			(start -0.299974 -0.150114)
			(end 0.299974 -0.150114)
			(stroke
				(width 0.1)
				(type default)
			)
			(layer "F.Fab")
		)
		(fp_line
			(start 0.299974 -0.150114)
			(end 0.299974 0.150114)
			(stroke
				(width 0.1)
				(type default)
			)
			(layer "F.Fab")
		)
		(pad "1" smd rect
			(at -0.2667 0 270)
			(size 0.3048 0.381)
			(layers "F.Cu" "F.Mask" "F.Paste")
			(net "P5E_CPU0_PE0_TX_C_DP<7>")
		)
		(pad "2" smd rect
			(at 0.2667 0 270)
			(size 0.3048 0.381)
			(layers "F.Cu" "F.Mask" "F.Paste")
			(net "P5E_CPU0_PE0_TX_DP<7>")
		)
	)
	(footprint ""
		(layer "F.Cu")
		(at 116.399056 -66.664078 -90)
		(property "Reference" "R930"
			(at 0 0 270)
			(layer "F.SilkS")
			(hide yes)
			(effects
				(font
					(size 1.27 1.27)
				)
			)
		)
		(property "Value" ""
			(at 0 0 270)
			(layer "F.Fab")
			(effects
				(font
					(size 1.27 1.27)
				)
			)
		)
		(duplicate_pad_numbers_are_jumpers no)
		(fp_line
			(start -0.7874 0.4064)
			(end -0.7874 -0.4064)
			(stroke
				(width 0.1524)
				(type default)
			)
			(layer "F.SilkS")
		)
		(fp_line
			(start 0.7874 0.4064)
			(end -0.7874 0.4064)
			(stroke
				(width 0.1524)
				(type default)
			)
			(layer "F.SilkS")
		)
		(fp_line
			(start -0.7874 -0.4064)
			(end 0.7874 -0.4064)
			(stroke
				(width 0.1524)
				(type default)
			)
			(layer "F.SilkS")
		)
		(fp_line
			(start 0.7874 -0.4064)
			(end 0.7874 0.4064)
			(stroke
				(width 0.1524)
				(type default)
			)
			(layer "F.SilkS")
		)
		(fp_line
			(start -0.67945 0.3048)
			(end -0.67945 -0.305054)
			(stroke
				(width 0.1)
				(type default)
			)
			(layer "F.Fab")
		)
		(fp_line
			(start -0.12065 0.3048)
			(end -0.67945 0.3048)
			(stroke
				(width 0.1)
				(type default)
			)
			(layer "F.Fab")
		)
		(fp_line
			(start 0.120396 0.3048)
			(end 0.120396 0.2794)
			(stroke
				(width 0.1)
				(type default)
			)
			(layer "F.Fab")
		)
		(fp_line
			(start 0.67945 0.3048)
			(end 0.120396 0.3048)
			(stroke
				(width 0.1)
				(type default)
			)
			(layer "F.Fab")
		)
		(fp_line
			(start -0.12065 0.2794)
			(end -0.12065 0.3048)
			(stroke
				(width 0.1)
				(type default)
			)
			(layer "F.Fab")
		)
		(fp_line
			(start 0.120396 0.2794)
			(end -0.12065 0.2794)
			(stroke
				(width 0.1)
				(type default)
			)
			(layer "F.Fab")
		)
		(fp_line
			(start -0.12065 -0.2794)
			(end 0.12065 -0.2794)
			(stroke
				(width 0.1)
				(type default)
			)
			(layer "F.Fab")
		)
		(fp_line
			(start 0.12065 -0.2794)
			(end 0.12065 -0.3048)
			(stroke
				(width 0.1)
				(type default)
			)
			(layer "F.Fab")
		)
		(fp_line
			(start 0.12065 -0.3048)
			(end 0.67945 -0.3048)
			(stroke
				(width 0.1)
				(type default)
			)
			(layer "F.Fab")
		)
		(fp_line
			(start 0.67945 -0.3048)
			(end 0.67945 0.3048)
			(stroke
				(width 0.1)
				(type default)
			)
			(layer "F.Fab")
		)
		(fp_line
			(start -0.67945 -0.305054)
			(end -0.12065 -0.305054)
			(stroke
				(width 0.1)
				(type default)
			)
			(layer "F.Fab")
		)
		(fp_line
			(start -0.12065 -0.305054)
			(end -0.12065 -0.2794)
			(stroke
				(width 0.1)
				(type default)
			)
			(layer "F.Fab")
		)
		(pad "1" smd circle
			(at -0.40005 0 270)
			(size 0 0)
			(layers "F.Cu" "F.Mask" "F.Paste")
			(net "JTAG_BMC_PLD_TCK")
		)
		(pad "2" smd circle
			(at 0.40005 0 270)
			(size 0 0)
			(layers "F.Cu" "F.Mask" "F.Paste")
			(net "GND")
		)
	)
	(footprint ""
		(layer "F.Cu")
		(at 218.336368 -61.072014 180)
		(property "Reference" "PC2218"
			(at 0 0 180)
			(layer "F.SilkS")
			(hide yes)
			(effects
				(font
					(size 1.27 1.27)
				)
			)
		)
		(property "Value" ""
			(at 0 0 180)
			(layer "F.Fab")
			(effects
				(font
					(size 1.27 1.27)
				)
			)
		)
		(duplicate_pad_numbers_are_jumpers no)
		(fp_line
			(start 0.7874 0.4064)
			(end -0.7874 0.4064)
			(stroke
				(width 0.1524)
				(type default)
			)
			(layer "F.SilkS")
		)
		(fp_line
			(start 0.7874 -0.4064)
			(end 0.7874 0.4064)
			(stroke
				(width 0.1524)
				(type default)
			)
			(layer "F.SilkS")
		)
		(fp_line
			(start -0.7874 0.4064)
			(end -0.7874 -0.4064)
			(stroke
				(width 0.1524)
				(type default)
			)
			(layer "F.SilkS")
		)
		(fp_line
			(start -0.7874 -0.4064)
			(end 0.7874 -0.4064)
			(stroke
				(width 0.1524)
				(type default)
			)
			(layer "F.SilkS")
		)
		(fp_line
			(start 0.67945 0.3048)
			(end 0.120396 0.3048)
			(stroke
				(width 0.1)
				(type default)
			)
			(layer "F.Fab")
		)
		(fp_line
			(start 0.67945 -0.3048)
			(end 0.67945 0.3048)
			(stroke
				(width 0.1)
				(type default)
			)
			(layer "F.Fab")
		)
		(fp_line
			(start 0.12065 -0.2794)
			(end 0.12065 -0.3048)
			(stroke
				(width 0.1)
				(type default)
			)
			(layer "F.Fab")
		)
		(fp_line
			(start 0.12065 -0.3048)
			(end 0.67945 -0.3048)
			(stroke
				(width 0.1)
				(type default)
			)
			(layer "F.Fab")
		)
		(fp_line
			(start 0.120396 0.3048)
			(end 0.120396 0.2794)
			(stroke
				(width 0.1)
				(type default)
			)
			(layer "F.Fab")
		)
		(fp_line
			(start 0.120396 0.2794)
			(end -0.12065 0.2794)
			(stroke
				(width 0.1)
				(type default)
			)
			(layer "F.Fab")
		)
		(fp_line
			(start -0.12065 0.3048)
			(end -0.67945 0.3048)
			(stroke
				(width 0.1)
				(type default)
			)
			(layer "F.Fab")
		)
		(fp_line
			(start -0.12065 0.2794)
			(end -0.12065 0.3048)
			(stroke
				(width 0.1)
				(type default)
			)
			(layer "F.Fab")
		)
		(fp_line
			(start -0.12065 -0.2794)
			(end 0.12065 -0.2794)
			(stroke
				(width 0.1)
				(type default)
			)
			(layer "F.Fab")
		)
		(fp_line
			(start -0.12065 -0.305054)
			(end -0.12065 -0.2794)
			(stroke
				(width 0.1)
				(type default)
			)
			(layer "F.Fab")
		)
		(fp_line
			(start -0.67945 0.3048)
			(end -0.67945 -0.305054)
			(stroke
				(width 0.1)
				(type default)
			)
			(layer "F.Fab")
		)
		(fp_line
			(start -0.67945 -0.305054)
			(end -0.12065 -0.305054)
			(stroke
				(width 0.1)
				(type default)
			)
			(layer "F.Fab")
		)
		(pad "1" smd circle
			(at -0.40005 0 180)
			(size 0 0)
			(layers "F.Cu" "F.Mask" "F.Paste")
			(net "P3V3_E1S_0_R")
		)
		(pad "2" smd circle
			(at 0.40005 0 180)
			(size 0 0)
			(layers "F.Cu" "F.Mask" "F.Paste")
			(net "GND")
		)
	)
	(footprint ""
		(layer "F.Cu")
		(at 322.263516 -23.551896 180)
		(property "Reference" "R1810"
			(at 0 0 180)
			(layer "F.SilkS")
			(hide yes)
			(effects
				(font
					(size 1.27 1.27)
				)
			)
		)
		(property "Value" ""
			(at 0 0 180)
			(layer "F.Fab")
			(effects
				(font
					(size 1.27 1.27)
				)
			)
		)
		(duplicate_pad_numbers_are_jumpers no)
		(fp_line
			(start 0.7874 0.4064)
			(end -0.7874 0.4064)
			(stroke
				(width 0.1524)
				(type default)
			)
			(layer "F.SilkS")
		)
		(fp_line
			(start 0.7874 -0.4064)
			(end 0.7874 0.4064)
			(stroke
				(width 0.1524)
				(type default)
			)
			(layer "F.SilkS")
		)
		(fp_line
			(start -0.7874 0.4064)
			(end -0.7874 -0.4064)
			(stroke
				(width 0.1524)
				(type default)
			)
			(layer "F.SilkS")
		)
		(fp_line
			(start -0.7874 -0.4064)
			(end 0.7874 -0.4064)
			(stroke
				(width 0.1524)
				(type default)
			)
			(layer "F.SilkS")
		)
		(fp_line
			(start 0.67945 0.3048)
			(end 0.120396 0.3048)
			(stroke
				(width 0.1)
				(type default)
			)
			(layer "F.Fab")
		)
		(fp_line
			(start 0.67945 -0.3048)
			(end 0.67945 0.3048)
			(stroke
				(width 0.1)
				(type default)
			)
			(layer "F.Fab")
		)
		(fp_line
			(start 0.12065 -0.2794)
			(end 0.12065 -0.3048)
			(stroke
				(width 0.1)
				(type default)
			)
			(layer "F.Fab")
		)
		(fp_line
			(start 0.12065 -0.3048)
			(end 0.67945 -0.3048)
			(stroke
				(width 0.1)
				(type default)
			)
			(layer "F.Fab")
		)
		(fp_line
			(start 0.120396 0.3048)
			(end 0.120396 0.2794)
			(stroke
				(width 0.1)
				(type default)
			)
			(layer "F.Fab")
		)
		(fp_line
			(start 0.120396 0.2794)
			(end -0.12065 0.2794)
			(stroke
				(width 0.1)
				(type default)
			)
			(layer "F.Fab")
		)
		(fp_line
			(start -0.12065 0.3048)
			(end -0.67945 0.3048)
			(stroke
				(width 0.1)
				(type default)
			)
			(layer "F.Fab")
		)
		(fp_line
			(start -0.12065 0.2794)
			(end -0.12065 0.3048)
			(stroke
				(width 0.1)
				(type default)
			)
			(layer "F.Fab")
		)
		(fp_line
			(start -0.12065 -0.2794)
			(end 0.12065 -0.2794)
			(stroke
				(width 0.1)
				(type default)
			)
			(layer "F.Fab")
		)
		(fp_line
			(start -0.12065 -0.305054)
			(end -0.12065 -0.2794)
			(stroke
				(width 0.1)
				(type default)
			)
			(layer "F.Fab")
		)
		(fp_line
			(start -0.67945 0.3048)
			(end -0.67945 -0.305054)
			(stroke
				(width 0.1)
				(type default)
			)
			(layer "F.Fab")
		)
		(fp_line
			(start -0.67945 -0.305054)
			(end -0.12065 -0.305054)
			(stroke
				(width 0.1)
				(type default)
			)
			(layer "F.Fab")
		)
		(pad "1" smd circle
			(at -0.40005 0 180)
			(size 0 0)
			(layers "F.Cu" "F.Mask" "F.Paste")
			(net "FM_ADR_MODE0")
		)
		(pad "2" smd circle
			(at 0.40005 0 180)
			(size 0 0)
			(layers "F.Cu" "F.Mask" "F.Paste")
			(net "GND")
		)
	)
	(footprint ""
		(layer "F.Cu")
		(at 185.799222 -23.113492)
		(property "Reference" "PR4000"
			(at 0 0 0)
			(layer "F.SilkS")
			(hide yes)
			(effects
				(font
					(size 1.27 1.27)
				)
			)
		)
		(property "Value" ""
			(at 0 0 0)
			(layer "F.Fab")
			(effects
				(font
					(size 1.27 1.27)
				)
			)
		)
		(duplicate_pad_numbers_are_jumpers no)
		(fp_line
			(start -0.7874 -0.4064)
			(end 0.7874 -0.4064)
			(stroke
				(width 0.1524)
				(type default)
			)
			(layer "F.SilkS")
		)
		(fp_line
			(start -0.7874 0.4064)
			(end -0.7874 -0.4064)
			(stroke
				(width 0.1524)
				(type default)
			)
			(layer "F.SilkS")
		)
		(fp_line
			(start 0.7874 -0.4064)
			(end 0.7874 0.4064)
			(stroke
				(width 0.1524)
				(type default)
			)
			(layer "F.SilkS")
		)
		(fp_line
			(start 0.7874 0.4064)
			(end -0.7874 0.4064)
			(stroke
				(width 0.1524)
				(type default)
			)
			(layer "F.SilkS")
		)
		(fp_line
			(start -0.67945 -0.305054)
			(end -0.12065 -0.305054)
			(stroke
				(width 0.1)
				(type default)
			)
			(layer "F.Fab")
		)
		(fp_line
			(start -0.67945 0.3048)
			(end -0.67945 -0.305054)
			(stroke
				(width 0.1)
				(type default)
			)
			(layer "F.Fab")
		)
		(fp_line
			(start -0.12065 -0.305054)
			(end -0.12065 -0.2794)
			(stroke
				(width 0.1)
				(type default)
			)
			(layer "F.Fab")
		)
		(fp_line
			(start -0.12065 -0.2794)
			(end 0.12065 -0.2794)
			(stroke
				(width 0.1)
				(type default)
			)
			(layer "F.Fab")
		)
		(fp_line
			(start -0.12065 0.2794)
			(end -0.12065 0.3048)
			(stroke
				(width 0.1)
				(type default)
			)
			(layer "F.Fab")
		)
		(fp_line
			(start -0.12065 0.3048)
			(end -0.67945 0.3048)
			(stroke
				(width 0.1)
				(type default)
			)
			(layer "F.Fab")
		)
		(fp_line
			(start 0.120396 0.2794)
			(end -0.12065 0.2794)
			(stroke
				(width 0.1)
				(type default)
			)
			(layer "F.Fab")
		)
		(fp_line
			(start 0.120396 0.3048)
			(end 0.120396 0.2794)
			(stroke
				(width 0.1)
				(type default)
			)
			(layer "F.Fab")
		)
		(fp_line
			(start 0.12065 -0.3048)
			(end 0.67945 -0.3048)
			(stroke
				(width 0.1)
				(type default)
			)
			(layer "F.Fab")
		)
		(fp_line
			(start 0.12065 -0.2794)
			(end 0.12065 -0.3048)
			(stroke
				(width 0.1)
				(type default)
			)
			(layer "F.Fab")
		)
		(fp_line
			(start 0.67945 -0.3048)
			(end 0.67945 0.3048)
			(stroke
				(width 0.1)
				(type default)
			)
			(layer "F.Fab")
		)
		(fp_line
			(start 0.67945 0.3048)
			(end 0.120396 0.3048)
			(stroke
				(width 0.1)
				(type default)
			)
			(layer "F.Fab")
		)
		(pad "1" smd circle
			(at -0.40005 0)
			(size 0 0)
			(layers "F.Cu" "F.Mask" "F.Paste")
			(net "P12V_AUX")
		)
		(pad "2" smd circle
			(at 0.40005 0)
			(size 0 0)
			(layers "F.Cu" "F.Mask" "F.Paste")
			(net "P12V_SCM_UV")
		)
	)
	(footprint ""
		(layer "F.Cu")
		(at 193.38036 -124.170948)
		(property "Reference" "C1325"
			(at 0 0 0)
			(layer "F.SilkS")
			(hide yes)
			(effects
				(font
					(size 1.27 1.27)
				)
			)
		)
		(property "Value" ""
			(at 0 0 0)
			(layer "F.Fab")
			(effects
				(font
					(size 1.27 1.27)
				)
			)
		)
		(duplicate_pad_numbers_are_jumpers no)
		(fp_line
			(start -0.7874 -0.4064)
			(end 0.7874 -0.4064)
			(stroke
				(width 0.1524)
				(type default)
			)
			(layer "F.SilkS")
		)
		(fp_line
			(start -0.7874 0.4064)
			(end -0.7874 -0.4064)
			(stroke
				(width 0.1524)
				(type default)
			)
			(layer "F.SilkS")
		)
		(fp_line
			(start 0.7874 -0.4064)
			(end 0.7874 0.4064)
			(stroke
				(width 0.1524)
				(type default)
			)
			(layer "F.SilkS")
		)
		(fp_line
			(start 0.7874 0.4064)
			(end -0.7874 0.4064)
			(stroke
				(width 0.1524)
				(type default)
			)
			(layer "F.SilkS")
		)
		(fp_line
			(start -0.67945 -0.305054)
			(end -0.12065 -0.305054)
			(stroke
				(width 0.1)
				(type default)
			)
			(layer "F.Fab")
		)
		(fp_line
			(start -0.67945 0.3048)
			(end -0.67945 -0.305054)
			(stroke
				(width 0.1)
				(type default)
			)
			(layer "F.Fab")
		)
		(fp_line
			(start -0.12065 -0.305054)
			(end -0.12065 -0.2794)
			(stroke
				(width 0.1)
				(type default)
			)
			(layer "F.Fab")
		)
		(fp_line
			(start -0.12065 -0.2794)
			(end 0.12065 -0.2794)
			(stroke
				(width 0.1)
				(type default)
			)
			(layer "F.Fab")
		)
		(fp_line
			(start -0.12065 0.2794)
			(end -0.12065 0.3048)
			(stroke
				(width 0.1)
				(type default)
			)
			(layer "F.Fab")
		)
		(fp_line
			(start -0.12065 0.3048)
			(end -0.67945 0.3048)
			(stroke
				(width 0.1)
				(type default)
			)
			(layer "F.Fab")
		)
		(fp_line
			(start 0.120396 0.2794)
			(end -0.12065 0.2794)
			(stroke
				(width 0.1)
				(type default)
			)
			(layer "F.Fab")
		)
		(fp_line
			(start 0.120396 0.3048)
			(end 0.120396 0.2794)
			(stroke
				(width 0.1)
				(type default)
			)
			(layer "F.Fab")
		)
		(fp_line
			(start 0.12065 -0.3048)
			(end 0.67945 -0.3048)
			(stroke
				(width 0.1)
				(type default)
			)
			(layer "F.Fab")
		)
		(fp_line
			(start 0.12065 -0.2794)
			(end 0.12065 -0.3048)
			(stroke
				(width 0.1)
				(type default)
			)
			(layer "F.Fab")
		)
		(fp_line
			(start 0.67945 -0.3048)
			(end 0.67945 0.3048)
			(stroke
				(width 0.1)
				(type default)
			)
			(layer "F.Fab")
		)
		(fp_line
			(start 0.67945 0.3048)
			(end 0.120396 0.3048)
			(stroke
				(width 0.1)
				(type default)
			)
			(layer "F.Fab")
		)
		(pad "1" smd circle
			(at -0.40005 0)
			(size 0 0)
			(layers "F.Cu" "F.Mask" "F.Paste")
			(net "FM_PLD_REV_N")
		)
		(pad "2" smd circle
			(at 0.40005 0)
			(size 0 0)
			(layers "F.Cu" "F.Mask" "F.Paste")
			(net "GND")
		)
	)
	(footprint ""
		(layer "F.Cu")
		(at 179.352448 -402.255482)
		(property "Reference" "PR3002"
			(at 0 0 0)
			(layer "F.SilkS")
			(hide yes)
			(effects
				(font
					(size 1.27 1.27)
				)
			)
		)
		(property "Value" ""
			(at 0 0 0)
			(layer "F.Fab")
			(effects
				(font
					(size 1.27 1.27)
				)
			)
		)
		(duplicate_pad_numbers_are_jumpers no)
		(fp_line
			(start -0.7874 -0.4064)
			(end 0.7874 -0.4064)
			(stroke
				(width 0.1524)
				(type default)
			)
			(layer "F.SilkS")
		)
		(fp_line
			(start -0.7874 0.4064)
			(end -0.7874 -0.4064)
			(stroke
				(width 0.1524)
				(type default)
			)
			(layer "F.SilkS")
		)
		(fp_line
			(start 0.7874 -0.4064)
			(end 0.7874 0.4064)
			(stroke
				(width 0.1524)
				(type default)
			)
			(layer "F.SilkS")
		)
		(fp_line
			(start 0.7874 0.4064)
			(end -0.7874 0.4064)
			(stroke
				(width 0.1524)
				(type default)
			)
			(layer "F.SilkS")
		)
		(fp_line
			(start -0.67945 -0.305054)
			(end -0.12065 -0.305054)
			(stroke
				(width 0.1)
				(type default)
			)
			(layer "F.Fab")
		)
		(fp_line
			(start -0.67945 0.3048)
			(end -0.67945 -0.305054)
			(stroke
				(width 0.1)
				(type default)
			)
			(layer "F.Fab")
		)
		(fp_line
			(start -0.12065 -0.305054)
			(end -0.12065 -0.2794)
			(stroke
				(width 0.1)
				(type default)
			)
			(layer "F.Fab")
		)
		(fp_line
			(start -0.12065 -0.2794)
			(end 0.12065 -0.2794)
			(stroke
				(width 0.1)
				(type default)
			)
			(layer "F.Fab")
		)
		(fp_line
			(start -0.12065 0.2794)
			(end -0.12065 0.3048)
			(stroke
				(width 0.1)
				(type default)
			)
			(layer "F.Fab")
		)
		(fp_line
			(start -0.12065 0.3048)
			(end -0.67945 0.3048)
			(stroke
				(width 0.1)
				(type default)
			)
			(layer "F.Fab")
		)
		(fp_line
			(start 0.120396 0.2794)
			(end -0.12065 0.2794)
			(stroke
				(width 0.1)
				(type default)
			)
			(layer "F.Fab")
		)
		(fp_line
			(start 0.120396 0.3048)
			(end 0.120396 0.2794)
			(stroke
				(width 0.1)
				(type default)
			)
			(layer "F.Fab")
		)
		(fp_line
			(start 0.12065 -0.3048)
			(end 0.67945 -0.3048)
			(stroke
				(width 0.1)
				(type default)
			)
			(layer "F.Fab")
		)
		(fp_line
			(start 0.12065 -0.2794)
			(end 0.12065 -0.3048)
			(stroke
				(width 0.1)
				(type default)
			)
			(layer "F.Fab")
		)
		(fp_line
			(start 0.67945 -0.3048)
			(end 0.67945 0.3048)
			(stroke
				(width 0.1)
				(type default)
			)
			(layer "F.Fab")
		)
		(fp_line
			(start 0.67945 0.3048)
			(end 0.120396 0.3048)
			(stroke
				(width 0.1)
				(type default)
			)
			(layer "F.Fab")
		)
		(pad "1" smd circle
			(at -0.40005 0)
			(size 0 0)
			(layers "F.Cu" "F.Mask" "F.Paste")
			(net "GND")
		)
		(pad "2" smd circle
			(at 0.40005 0)
			(size 0 0)
			(layers "F.Cu" "F.Mask" "F.Paste")
			(net "AGND_HSC")
		)
	)
)
